(kicad_pcb
	(version 20241229)
	(generator "pcbnew")
	(generator_version "9.0")
	(general
		(thickness 1.711)
		(legacy_teardrops no)
	)
	(paper "A4")
	(title_block
		(title "Antmicro Baseboard for Jetson AGX Thor")
		(date "2026-02-18")
		(rev "1.1.0")
		(company "Antmicro Ltd")
		(comment 1 "www.antmicro.com")
		(comment 9 "footprints 183-186 of 1170")
	)
	(layers
		(0 "F.Cu" signal)
		(4 "In1.Cu" signal)
		(6 "In2.Cu" signal)
		(8 "In3.Cu" signal)
		(10 "In4.Cu" jumper)
		(12 "In5.Cu" signal)
		(14 "In6.Cu" signal)
		(16 "In7.Cu" signal)
		(18 "In8.Cu" signal)
		(2 "B.Cu" signal)
		(9 "F.Adhes" user "F.Adhesive")
		(11 "B.Adhes" user "B.Adhesive")
		(13 "F.Paste" user)
		(15 "B.Paste" user)
		(5 "F.SilkS" user "F.Silkscreen")
		(7 "B.SilkS" user "B.Silkscreen")
		(1 "F.Mask" user)
		(3 "B.Mask" user)
		(17 "Dwgs.User" user "User.Drawings")
		(19 "Cmts.User" user "User.Comments")
		(21 "Eco1.User" user "User.Eco1")
		(23 "Eco2.User" user "User.Eco2")
		(25 "Edge.Cuts" user)
		(27 "Margin" user)
		(31 "F.CrtYd" user "F.Courtyard")
		(29 "B.CrtYd" user "B.Courtyard")
		(35 "F.Fab" user)
		(33 "B.Fab" user)
	)
	(footprint "antmicro-footprints:R_0402_1005Metric"
		(layer "F.Cu")
		(at 216.8 120.1 90)
		(descr "Resistor SMD 0402")
		(tags "resistor SMD 0402")
		(property "Reference" "R87"
			(at 0.8 0.4 90)
			(layer "F.SilkS")
			(effects
				(font
					(size 0.7 0.7)
					(thickness 0.15)
				)
				(justify left bottom)
			)
		)
		(property "Value" "R_10k_0402"
			(at -1.011843 1.772046 90)
			(layer "F.Fab")
			(effects
				(font
					(size 0.7 0.7)
					(thickness 0.15)
				)
				(justify left bottom)
			)
		)
		(property "Datasheet" "https://www.bourns.com/docs/product-datasheets/cr.pdf"
			(at 0 0 90)
			(layer "F.Fab")
			(hide yes)
			(effects
				(font
					(size 1.27 1.27)
					(thickness 0.15)
				)
			)
		)
		(property "Description" "SMD Chip Resistor, 10 kohm, ± 1%, 62.5 mW, 0402 [1005 Metric], Thick Film, General Purpose"
			(at 0 0 90)
			(layer "F.Fab")
			(hide yes)
			(effects
				(font
					(size 1.27 1.27)
					(thickness 0.15)
				)
			)
		)
		(property "Manufacturer" "Bourns"
			(at 0 0 90)
			(unlocked yes)
			(layer "F.Fab")
			(hide yes)
			(effects
				(font
					(size 1 1)
					(thickness 0.15)
				)
			)
		)
		(property "MPN" "CR0402-FX-1002GLF"
			(at 0 0 90)
			(unlocked yes)
			(layer "F.Fab")
			(hide yes)
			(effects
				(font
					(size 1 1)
					(thickness 0.15)
				)
			)
		)
		(property "Val" "10k"
			(at 0 0 90)
			(unlocked yes)
			(layer "F.Fab")
			(hide yes)
			(effects
				(font
					(size 1 1)
					(thickness 0.15)
				)
			)
		)
		(property "License" "Apache-2.0"
			(at 0 0 90)
			(unlocked yes)
			(layer "F.Fab")
			(hide yes)
			(effects
				(font
					(size 1 1)
					(thickness 0.15)
				)
			)
		)
		(property "Author" "Antmicro"
			(at 0 0 90)
			(unlocked yes)
			(layer "F.Fab")
			(hide yes)
			(effects
				(font
					(size 1 1)
					(thickness 0.15)
				)
			)
		)
		(property "Tolerance" "1%"
			(at 0 0 90)
			(unlocked yes)
			(layer "F.Fab")
			(hide yes)
			(effects
				(font
					(size 1 1)
					(thickness 0.15)
				)
			)
		)
		(sheetname "/USB Hub/")
		(sheetfile "usb_hub.kicad_sch")
		(attr smd)
		(fp_poly
			(pts
				(xy -0.925 -0.47) (xy 0.925 -0.47) (xy 0.925 0.47) (xy -0.925 0.47)
			)
			(stroke
				(width 0.05)
				(type default)
			)
			(fill no)
			(layer "F.CrtYd")
		)
		(fp_poly
			(pts
				(xy -0.5 -0.25) (xy 0.5 -0.25) (xy 0.5 0.25) (xy -0.5 0.25)
			)
			(stroke
				(width 0.15)
				(type solid)
			)
			(fill no)
			(layer "F.Fab")
		)
		(fp_text user "${REFERENCE}"
			(at -0.95 3.168 90)
			(layer "F.Fab")
			(effects
				(font
					(size 0.7 0.7)
					(thickness 0.15)
				)
				(justify left bottom)
			)
		)
		(fp_text user "Author: Antmicro"
			(at -0.95 4.169 90)
			(layer "F.Fab")
			(effects
				(font
					(size 0.7 0.7)
					(thickness 0.15)
				)
				(justify left bottom)
			)
		)
		(fp_text user "License: Apache-2.0"
			(at -0.949999 5.169 90)
			(layer "F.Fab")
			(effects
				(font
					(size 0.7 0.7)
					(thickness 0.15)
				)
				(justify left bottom)
			)
		)
		(pad "1" smd roundrect
			(at -0.48 0 90)
			(size 0.59 0.64)
			(layers "F.Cu" "F.Mask" "F.Paste")
			(roundrect_rratio 0.25)
			(net 913 "/USB Hub/CFG_STRAP1")
			(pintype "passive")
		)
		(pad "2" smd roundrect
			(at 0.48 0 90)
			(size 0.59 0.64)
			(layers "F.Cu" "F.Mask" "F.Paste")
			(roundrect_rratio 0.25)
			(net 2 "+3V3")
			(pintype "passive")
		)
	)
	(footprint "antmicro-footprints:R_0402_1005Metric"
		(layer "F.Cu")
		(at 96.45 55.87 180)
		(descr "Resistor SMD 0402")
		(tags "resistor SMD 0402")
		(property "Reference" "R305"
			(at 0.85 0.42 0)
			(layer "F.SilkS")
			(effects
				(font
					(size 0.7 0.7)
					(thickness 0.15)
				)
				(justify right top)
			)
		)
		(property "Value" "R_10k_0402"
			(at -1.011843 1.772047 0)
			(layer "F.Fab")
			(effects
				(font
					(size 0.7 0.7)
					(thickness 0.15)
				)
				(justify right top)
			)
		)
		(property "Datasheet" "https://www.bourns.com/docs/product-datasheets/cr.pdf"
			(at 0 0 0)
			(layer "F.Fab")
			(hide yes)
			(effects
				(font
					(size 1.27 1.27)
					(thickness 0.15)
				)
			)
		)
		(property "Description" "SMD Chip Resistor, 10 kohm, ± 1%, 62.5 mW, 0402 [1005 Metric], Thick Film, General Purpose"
			(at 0 0 0)
			(layer "F.Fab")
			(hide yes)
			(effects
				(font
					(size 1.27 1.27)
					(thickness 0.15)
				)
			)
		)
		(property "MPN" "CR0402-FX-1002GLF"
			(at 0 0 180)
			(unlocked yes)
			(layer "F.Fab")
			(hide yes)
			(effects
				(font
					(size 1 1)
					(thickness 0.15)
				)
			)
		)
		(property "Manufacturer" "Bourns"
			(at 0 0 180)
			(unlocked yes)
			(layer "F.Fab")
			(hide yes)
			(effects
				(font
					(size 1 1)
					(thickness 0.15)
				)
			)
		)
		(property "License" "Apache-2.0"
			(at 0 0 180)
			(unlocked yes)
			(layer "F.Fab")
			(hide yes)
			(effects
				(font
					(size 1 1)
					(thickness 0.15)
				)
			)
		)
		(property "Author" "Antmicro"
			(at 0 0 180)
			(unlocked yes)
			(layer "F.Fab")
			(hide yes)
			(effects
				(font
					(size 1 1)
					(thickness 0.15)
				)
			)
		)
		(property "Val" "10k"
			(at 0 0 180)
			(unlocked yes)
			(layer "F.Fab")
			(hide yes)
			(effects
				(font
					(size 1 1)
					(thickness 0.15)
				)
			)
		)
		(property "Tolerance" "1%"
			(at 0 0 180)
			(unlocked yes)
			(layer "F.Fab")
			(hide yes)
			(effects
				(font
					(size 1 1)
					(thickness 0.15)
				)
			)
		)
		(sheetname "/SoM_Power/")
		(sheetfile "som_power.kicad_sch")
		(attr smd)
		(fp_rect
			(start -0.925 -0.47)
			(end 0.925 0.47)
			(stroke
				(width 0.05)
				(type default)
			)
			(fill no)
			(layer "F.CrtYd")
		)
		(fp_rect
			(start -0.5 -0.25)
			(end 0.5 0.25)
			(stroke
				(width 0.15)
				(type solid)
			)
			(fill no)
			(layer "F.Fab")
		)
		(fp_text user "Author: Antmicro"
			(at -0.95 4.169 0)
			(layer "F.Fab")
			(effects
				(font
					(size 0.7 0.7)
					(thickness 0.15)
				)
				(justify right top)
			)
		)
		(fp_text user "License: Apache-2.0"
			(at -0.95 5.169 0)
			(layer "F.Fab")
			(effects
				(font
					(size 0.7 0.7)
					(thickness 0.15)
				)
				(justify right top)
			)
		)
		(fp_text user "${REFERENCE}"
			(at -0.95 3.168 0)
			(layer "F.Fab")
			(effects
				(font
					(size 0.7 0.7)
					(thickness 0.15)
				)
				(justify right top)
			)
		)
		(pad "1" smd roundrect
			(at -0.48 0 180)
			(size 0.59 0.64)
			(layers "F.Cu" "F.Mask" "F.Paste")
			(roundrect_rratio 0.25)
			(net 1 "GND")
			(pintype "passive")
		)
		(pad "2" smd roundrect
			(at 0.48 0 180)
			(size 0.59 0.64)
			(layers "F.Cu" "F.Mask" "F.Paste")
			(roundrect_rratio 0.25)
			(net 1380 "Net-(U3-DIV)")
			(pintype "passive")
		)
	)
	(footprint "antmicro-footprints:C_0402_1005Metric"
		(layer "F.Cu")
		(at 88 63.5 180)
		(descr "Capacitor SMD 0402")
		(tags "capacitor SMD 0402")
		(property "Reference" "C236"
			(at 16.3 -8.7 180)
			(layer "F.SilkS")
			(effects
				(font
					(size 0.7 0.7)
					(thickness 0.15)
				)
				(justify right top)
			)
		)
		(property "Value" "C_100n_0402"
			(at -1.022927 2.155213 0)
			(layer "F.Fab")
			(effects
				(font
					(size 0.7 0.7)
					(thickness 0.15)
				)
				(justify right top)
			)
		)
		(property "Datasheet" "https://www.murata.com/products/productdetail?partno=GRM155R61H104KE14%23"
			(at 0 0 0)
			(layer "F.Fab")
			(hide yes)
			(effects
				(font
					(size 1.27 1.27)
					(thickness 0.15)
				)
			)
		)
		(property "Description" "SMD Multilayer Ceramic Capacitor, 0.1 µF, 50 V, 0402 [1005 Metric], ± 10%, X5R, GRM Series"
			(at 0 0 0)
			(layer "F.Fab")
			(hide yes)
			(effects
				(font
					(size 1.27 1.27)
					(thickness 0.15)
				)
			)
		)
		(property "MPN" "GRM155R61H104KE14D"
			(at 0 0 180)
			(unlocked yes)
			(layer "F.Fab")
			(hide yes)
			(effects
				(font
					(size 1 1)
					(thickness 0.15)
				)
			)
		)
		(property "Manufacturer" "Murata"
			(at 0 0 180)
			(unlocked yes)
			(layer "F.Fab")
			(hide yes)
			(effects
				(font
					(size 1 1)
					(thickness 0.15)
				)
			)
		)
		(property "License" "Apache-2.0"
			(at 0 0 180)
			(unlocked yes)
			(layer "F.Fab")
			(hide yes)
			(effects
				(font
					(size 1 1)
					(thickness 0.15)
				)
			)
		)
		(property "Author" "Antmicro"
			(at 0 0 180)
			(unlocked yes)
			(layer "F.Fab")
			(hide yes)
			(effects
				(font
					(size 1 1)
					(thickness 0.15)
				)
			)
		)
		(property "Val" "100n"
			(at 0 0 180)
			(unlocked yes)
			(layer "F.Fab")
			(hide yes)
			(effects
				(font
					(size 1 1)
					(thickness 0.15)
				)
			)
		)
		(property "Voltage" "50V"
			(at 0 0 180)
			(unlocked yes)
			(layer "F.Fab")
			(hide yes)
			(effects
				(font
					(size 1 1)
					(thickness 0.15)
				)
			)
		)
		(property "Dielectric" "X5R"
			(at 0 0 180)
			(unlocked yes)
			(layer "F.Fab")
			(hide yes)
			(effects
				(font
					(size 1 1)
					(thickness 0.15)
				)
			)
		)
		(sheetname "/SoM_Power/")
		(sheetfile "som_power.kicad_sch")
		(attr smd)
		(fp_rect
			(start -0.925 -0.47)
			(end 0.925 0.47)
			(stroke
				(width 0.05)
				(type default)
			)
			(fill no)
			(layer "F.CrtYd")
		)
		(fp_line
			(start 0.504 0.248)
			(end -0.494 0.248)
			(stroke
				(width 0.15)
				(type solid)
			)
			(layer "F.Fab")
		)
		(fp_line
			(start 0.504 -0.25)
			(end 0.504 0.248)
			(stroke
				(width 0.15)
				(type solid)
			)
			(layer "F.Fab")
		)
		(fp_line
			(start -0.494 0.248)
			(end -0.494 -0.25)
			(stroke
				(width 0.15)
				(type solid)
			)
			(layer "F.Fab")
		)
		(fp_line
			(start -0.494 -0.25)
			(end 0.504 -0.25)
			(stroke
				(width 0.15)
				(type solid)
			)
			(layer "F.Fab")
		)
		(fp_text user "Author: Antmicro"
			(at -0.939 3.399 0)
			(layer "F.Fab")
			(effects
				(font
					(size 0.7 0.7)
					(thickness 0.15)
				)
				(justify right top)
			)
		)
		(fp_text user "${REFERENCE}"
			(at -0.939 4.599 0)
			(layer "F.Fab")
			(effects
				(font
					(size 0.7 0.7)
					(thickness 0.15)
				)
				(justify right top)
			)
		)
		(fp_text user "License: Apache-2.0"
			(at -0.939 5.799 0)
			(layer "F.Fab")
			(effects
				(font
					(size 0.7 0.7)
					(thickness 0.15)
				)
				(justify right top)
			)
		)
		(pad "1" smd roundrect
			(at -0.48 0 180)
			(size 0.59 0.64)
			(layers "F.Cu" "F.Mask" "F.Paste")
			(roundrect_rratio 0.25)
			(net 1 "GND")
			(pintype "passive")
		)
		(pad "2" smd roundrect
			(at 0.48 0 180)
			(size 0.59 0.64)
			(layers "F.Cu" "F.Mask" "F.Paste")
			(roundrect_rratio 0.25)
			(net 246 "/SoM_Power/~{VDDIN_PWR_BAD}")
			(pintype "passive")
		)
	)
	(footprint "antmicro-footprints:LED_0603_1608Metric_G"
		(layer "F.Cu")
		(at 170.75 55.3 -90)
		(descr "LED SMD 0603 Green")
		(tags "LED SMD 0603 Green")
		(property "Reference" "D12"
			(at -0.85 1.6 90)
			(layer "F.SilkS")
			(effects
				(font
					(size 0.7 0.7)
					(thickness 0.15)
				)
				(justify right top)
			)
		)
		(property "Value" "LED_G_0603_LTST-C190GKT"
			(at -0.001 1.599 90)
			(layer "F.Fab")
			(effects
				(font
					(size 0.7 0.7)
					(thickness 0.15)
				)
				(justify right top)
			)
		)
		(property "Datasheet" "https://media.digikey.com/pdf/Data%20Sheets/Lite-On%20PDFs/LTST-C190GKT.pdf"
			(at 0 0 90)
			(layer "F.Fab")
			(hide yes)
			(effects
				(font
					(size 1.27 1.27)
					(thickness 0.15)
				)
			)
		)
		(property "Description" "LED, Green, SMD, 0603, 20 mA, 2.1 V, 569 nm"
			(at 0 0 90)
			(layer "F.Fab")
			(hide yes)
			(effects
				(font
					(size 1.27 1.27)
					(thickness 0.15)
				)
			)
		)
		(property "MPN" "LTST-C190GKT"
			(at 0 0 270)
			(unlocked yes)
			(layer "F.Fab")
			(hide yes)
			(effects
				(font
					(size 1 1)
					(thickness 0.15)
				)
			)
		)
		(property "Manufacturer" "Lite-On"
			(at 0 0 270)
			(unlocked yes)
			(layer "F.Fab")
			(hide yes)
			(effects
				(font
					(size 1 1)
					(thickness 0.15)
				)
			)
		)
		(property "Author" "Antmicro"
			(at 0 0 270)
			(unlocked yes)
			(layer "F.Fab")
			(hide yes)
			(effects
				(font
					(size 1 1)
					(thickness 0.15)
				)
			)
		)
		(property "License" "Apache-2.0"
			(at 0 0 270)
			(unlocked yes)
			(layer "F.Fab")
			(hide yes)
			(effects
				(font
					(size 1 1)
					(thickness 0.15)
				)
			)
		)
		(property "Color" "Green"
			(at 0 0 270)
			(unlocked yes)
			(layer "F.Fab")
			(hide yes)
			(effects
				(font
					(size 1 1)
					(thickness 0.15)
				)
			)
		)
		(sheetname "/Power/")
		(sheetfile "power.kicad_sch")
		(attr smd)
		(fp_line
			(start 0.22 0.35)
			(end -0.22 0.35)
			(stroke
				(width 0.15)
				(type solid)
			)
			(layer "F.SilkS")
		)
		(fp_line
			(start -0.094672 0.201008)
			(end -0.094672 -0.198992)
			(stroke
				(width 0.1)
				(type solid)
			)
			(layer "F.SilkS")
		)
		(fp_line
			(start 0.105328 0.201008)
			(end -0.094672 0.001008)
			(stroke
				(width 0.1)
				(type solid)
			)
			(layer "F.SilkS")
		)
		(fp_line
			(start 0.105328 0.201008)
			(end 0.105328 -0.198992)
			(stroke
				(width 0.1)
				(type solid)
			)
			(layer "F.SilkS")
		)
		(fp_line
			(start -0.094672 0.001008)
			(end -0.24 0.001008)
			(stroke
				(width 0.1)
				(type solid)
			)
			(layer "F.SilkS")
		)
		(fp_line
			(start -0.094672 0.001008)
			(end 0.105328 -0.198992)
			(stroke
				(width 0.1)
				(type solid)
			)
			(layer "F.SilkS")
		)
		(fp_line
			(start 0.105328 0.001008)
			(end 0.24 0.001)
			(stroke
				(width 0.1)
				(type solid)
			)
			(layer "F.SilkS")
		)
		(fp_line
			(start -1.18 -0.319)
			(end -1.18 0.321)
			(stroke
				(width 0.15)
				(type solid)
			)
			(layer "F.SilkS")
		)
		(fp_line
			(start 0.22 -0.35)
			(end -0.22 -0.35)
			(stroke
				(width 0.15)
				(type solid)
			)
			(layer "F.SilkS")
		)
		(fp_rect
			(start 1.25 0.65)
			(end -1.25 -0.65)
			(stroke
				(width 0.05)
				(type solid)
			)
			(fill no)
			(layer "F.CrtYd")
		)
		(fp_line
			(start -0.199 0.2)
			(end -0.199 0.1)
			(stroke
				(width 0.15)
				(type solid)
			)
			(layer "F.Fab")
		)
		(fp_line
			(start 0.201 0.2)
			(end 0.201 0)
			(stroke
				(width 0.15)
				(type solid)
			)
			(layer "F.Fab")
		)
		(fp_line
			(start -0.199 0)
			(end -0.597 0)
			(stroke
				(width 0.15)
				(type solid)
			)
			(layer "F.Fab")
		)
		(fp_line
			(start -0.101 0)
			(end 0.201 0.2)
			(stroke
				(width 0.15)
				(type solid)
			)
			(layer "F.Fab")
		)
		(fp_line
			(start 0.201 0)
			(end 0.201 -0.202)
			(stroke
				(width 0.15)
				(type solid)
			)
			(layer "F.Fab")
		)
		(fp_line
			(start 0.599 0)
			(end 0.201 0)
			(stroke
				(width 0.15)
				(type solid)
			)
			(layer "F.Fab")
		)
		(fp_line
			(start -0.199 -0.202)
			(end -0.199 0.1)
			(stroke
				(width 0.15)
				(type solid)
			)
			(layer "F.Fab")
		)
		(fp_line
			(start 0.201 -0.202)
			(end -0.101 0)
			(stroke
				(width 0.15)
				(type solid)
			)
			(layer "F.Fab")
		)
		(fp_rect
			(start 0.848 0.4)
			(end -0.85 -0.402)
			(stroke
				(width 0.15)
				(type solid)
			)
			(fill no)
			(layer "F.Fab")
		)
		(fp_text user "License: Apache-2.0"
			(at -1.4224 3.599 90)
			(layer "F.Fab")
			(effects
				(font
					(size 0.7 0.7)
					(thickness 0.15)
				)
				(justify right top)
			)
		)
		(fp_text user "Author: Antmicro"
			(at -1.4224 4.799 90)
			(layer "F.Fab")
			(effects
				(font
					(size 0.7 0.7)
					(thickness 0.15)
				)
				(justify right top)
			)
		)
		(fp_text user "${REFERENCE}"
			(at -1.4224 5.999 90)
			(layer "F.Fab")
			(effects
				(font
					(size 0.7 0.7)
					(thickness 0.15)
				)
				(justify right top)
			)
		)
		(pad "1" smd roundrect
			(at -0.7 0 90)
			(size 0.8 1)
			(layers "F.Cu" "F.Mask" "F.Paste")
			(roundrect_rratio 0.2)
			(net 1 "GND")
			(pinfunction "C")
			(pintype "passive")
		)
		(pad "2" smd roundrect
			(at 0.7 0 90)
			(size 0.8 1)
			(layers "F.Cu" "F.Mask" "F.Paste")
			(roundrect_rratio 0.2)
			(net 490 "Net-(D12-A)")
			(pinfunction "A")
			(pintype "passive")
		)
	)
)
